# S9S_MB_2U (Grand Teton) — schematic netlist excerpt (pin names and nets, part order shuffled) for the footprints in the layout excerpt that follows; sources: Cadence DE-HDL packaged netlist, KiCad conversion of 03242023_DA0F0TMBIJ0_F0T_Motherboard_J_brd_V01_OCP.brd

C1921  Q_CAP  22UF 6.3V 20% X6S  pkg C0603  page 190 : A = P3V3_M2_0 ; B = GND
PC1365  Q_CAP  0.1UF 25V 10% X7R  pkg 0402  page 293 : A = GND ; B = PVCCINFAON_CPU1_VREF

(kicad_pcb
	(version 20260206)
	(generator "pcbnew")
	(generator_version "10.0")
	(general
		(thickness 1.6)
		(legacy_teardrops no)
	)
	(paper "A4")
	(title_block
		(title "03242023_DA0F0TMBIJ0_F0T_Motherboard_J_brd_V01_OCP.brd")
		(comment 1 "Grand Teton / footprints 4118-4119 of 6105")
	)
	(layers
		(0 "F.Cu" signal "TOP")
		(4 "In1.Cu" signal "GND")
		(6 "In2.Cu" signal "IN1")
		(8 "In3.Cu" signal "GND1")
		(10 "In4.Cu" signal "IN2")
		(12 "In5.Cu" signal "GND2")
		(14 "In6.Cu" signal "IN3")
		(16 "In7.Cu" signal "GND3")
		(18 "In8.Cu" signal "VCC")
		(20 "In9.Cu" signal "VCC1")
		(22 "In10.Cu" signal "GND4")
		(24 "In11.Cu" signal "IN4")
		(26 "In12.Cu" signal "GND5")
		(28 "In13.Cu" signal "IN5")
		(30 "In14.Cu" signal "GND6")
		(32 "In15.Cu" signal "IN6")
		(34 "In16.Cu" signal "GND7")
		(2 "B.Cu" signal "BOTTOM")
		(9 "F.Adhes" user "F.Adhesive")
		(11 "B.Adhes" user "B.Adhesive")
		(13 "F.Paste" user "Package Geometry/Pastemask Top")
		(15 "B.Paste" user "Package Geometry/Pastemask Bottom")
		(5 "F.SilkS" user "Ref Des/Silkscreen Top")
		(7 "B.SilkS" user "Ref Des/Silkscreen Bottom")
		(1 "F.Mask" user "Board Geometry/Soldermask Top")
		(3 "B.Mask" user "Board Geometry/Soldermask Bottom")
		(17 "Dwgs.User" user "User.Drawings")
		(19 "Cmts.User" user "User.Comments")
		(21 "Eco1.User" user "User.Eco1")
		(23 "Eco2.User" user "User.Eco2")
		(25 "Edge.Cuts" user "Board Geometry/Outline")
		(27 "Margin" user)
		(31 "F.CrtYd" user "Package Geometry/Place Bound Top")
		(29 "B.CrtYd" user "Package Geometry/Place Bound Bottom")
		(35 "F.Fab" user "Ref Des/Assembly Top")
		(33 "B.Fab" user "Ref Des/Assembly Bottom")
	)
	(footprint ""
		(layer "F.Cu")
		(at 166.859204 -56.819038 90)
		(property "Reference" "C1921"
			(at 0 0 90)
			(layer "F.SilkS")
			(hide yes)
			(effects
				(font
					(size 1.27 1.27)
				)
			)
		)
		(property "Value" ""
			(at 0 0 90)
			(layer "F.Fab")
			(effects
				(font
					(size 1.27 1.27)
				)
			)
		)
		(duplicate_pad_numbers_are_jumpers no)
		(fp_line
			(start 1.2954 -0.5842)
			(end 1.2954 0.5842)
			(stroke
				(width 0.1524)
				(type default)
			)
			(layer "F.SilkS")
		)
		(fp_line
			(start 0 -0.5842)
			(end 0 0.5842)
			(stroke
				(width 0.1524)
				(type default)
			)
			(layer "F.SilkS")
		)
		(fp_line
			(start -1.2954 -0.5842)
			(end 1.2954 -0.5842)
			(stroke
				(width 0.1524)
				(type default)
			)
			(layer "F.SilkS")
		)
		(fp_line
			(start 1.2954 0.5842)
			(end -1.2954 0.5842)
			(stroke
				(width 0.1524)
				(type default)
			)
			(layer "F.SilkS")
		)
		(fp_line
			(start -1.2954 0.5842)
			(end -1.2954 -0.5842)
			(stroke
				(width 0.1524)
				(type default)
			)
			(layer "F.SilkS")
		)
		(fp_line
			(start 0.8636 -0.4572)
			(end 0.8636 -0.4064)
			(stroke
				(width 0.1)
				(type default)
			)
			(layer "F.Fab")
		)
		(fp_line
			(start -0.8636 -0.4572)
			(end 0.8636 -0.4572)
			(stroke
				(width 0.1)
				(type default)
			)
			(layer "F.Fab")
		)
		(fp_line
			(start 1.1938 -0.4064)
			(end 1.1938 0.4064)
			(stroke
				(width 0.1)
				(type default)
			)
			(layer "F.Fab")
		)
		(fp_line
			(start 0.8636 -0.4064)
			(end 1.1938 -0.4064)
			(stroke
				(width 0.1)
				(type default)
			)
			(layer "F.Fab")
		)
		(fp_line
			(start -0.8636 -0.4064)
			(end -0.8636 -0.4572)
			(stroke
				(width 0.1)
				(type default)
			)
			(layer "F.Fab")
		)
		(fp_line
			(start -1.1938 -0.4064)
			(end -0.8636 -0.4064)
			(stroke
				(width 0.1)
				(type default)
			)
			(layer "F.Fab")
		)
		(fp_line
			(start 1.1938 0.4064)
			(end 0.8636 0.4064)
			(stroke
				(width 0.1)
				(type default)
			)
			(layer "F.Fab")
		)
		(fp_line
			(start 0.8636 0.4064)
			(end 0.8636 0.4572)
			(stroke
				(width 0.1)
				(type default)
			)
			(layer "F.Fab")
		)
		(fp_line
			(start -0.8636 0.4064)
			(end -1.1938 0.4064)
			(stroke
				(width 0.1)
				(type default)
			)
			(layer "F.Fab")
		)
		(fp_line
			(start -1.1938 0.4064)
			(end -1.1938 -0.4064)
			(stroke
				(width 0.1)
				(type default)
			)
			(layer "F.Fab")
		)
		(fp_line
			(start 0.8636 0.4572)
			(end -0.8636 0.4572)
			(stroke
				(width 0.1)
				(type default)
			)
			(layer "F.Fab")
		)
		(fp_line
			(start -0.8636 0.4572)
			(end -0.8636 0.4064)
			(stroke
				(width 0.1)
				(type default)
			)
			(layer "F.Fab")
		)
		(pad "1" smd rect
			(at -0.7366 0)
			(size 0.7112 0.8128)
			(layers "F.Cu" "F.Mask" "F.Paste")
			(net "P3V3_M2_0")
		)
		(pad "2" smd rect
			(at 0.7366 0)
			(size 0.7112 0.8128)
			(layers "F.Cu" "F.Mask" "F.Paste")
			(net "GND")
		)
	)
	(footprint ""
		(layer "F.Cu")
		(at 50.317654 -145.008854)
		(property "Reference" "PC1365"
			(at 0 0 0)
			(layer "F.SilkS")
			(hide yes)
			(effects
				(font
					(size 1.27 1.27)
				)
			)
		)
		(property "Value" ""
			(at 0 0 0)
			(layer "F.Fab")
			(effects
				(font
					(size 1.27 1.27)
				)
			)
		)
		(duplicate_pad_numbers_are_jumpers no)
		(fp_line
			(start -0.7874 -0.4064)
			(end 0.7874 -0.4064)
			(stroke
				(width 0.1524)
				(type default)
			)
			(layer "F.SilkS")
		)
		(fp_line
			(start -0.7874 0.4064)
			(end -0.7874 -0.4064)
			(stroke
				(width 0.1524)
				(type default)
			)
			(layer "F.SilkS")
		)
		(fp_line
			(start 0.7874 -0.4064)
			(end 0.7874 0.4064)
			(stroke
				(width 0.1524)
				(type default)
			)
			(layer "F.SilkS")
		)
		(fp_line
			(start 0.7874 0.4064)
			(end -0.7874 0.4064)
			(stroke
				(width 0.1524)
				(type default)
			)
			(layer "F.SilkS")
		)
		(fp_line
			(start -0.67945 -0.305054)
			(end -0.12065 -0.305054)
			(stroke
				(width 0.1)
				(type default)
			)
			(layer "F.Fab")
		)
		(fp_line
			(start -0.67945 0.3048)
			(end -0.67945 -0.305054)
			(stroke
				(width 0.1)
				(type default)
			)
			(layer "F.Fab")
		)
		(fp_line
			(start -0.12065 -0.305054)
			(end -0.12065 -0.2794)
			(stroke
				(width 0.1)
				(type default)
			)
			(layer "F.Fab")
		)
		(fp_line
			(start -0.12065 -0.2794)
			(end 0.12065 -0.2794)
			(stroke
				(width 0.1)
				(type default)
			)
			(layer "F.Fab")
		)
		(fp_line
			(start -0.12065 0.2794)
			(end -0.12065 0.3048)
			(stroke
				(width 0.1)
				(type default)
			)
			(layer "F.Fab")
		)
		(fp_line
			(start -0.12065 0.3048)
			(end -0.67945 0.3048)
			(stroke
				(width 0.1)
				(type default)
			)
			(layer "F.Fab")
		)
		(fp_line
			(start 0.120396 0.2794)
			(end -0.12065 0.2794)
			(stroke
				(width 0.1)
				(type default)
			)
			(layer "F.Fab")
		)
		(fp_line
			(start 0.120396 0.3048)
			(end 0.120396 0.2794)
			(stroke
				(width 0.1)
				(type default)
			)
			(layer "F.Fab")
		)
		(fp_line
			(start 0.12065 -0.3048)
			(end 0.67945 -0.3048)
			(stroke
				(width 0.1)
				(type default)
			)
			(layer "F.Fab")
		)
		(fp_line
			(start 0.12065 -0.2794)
			(end 0.12065 -0.3048)
			(stroke
				(width 0.1)
				(type default)
			)
			(layer "F.Fab")
		)
		(fp_line
			(start 0.67945 -0.3048)
			(end 0.67945 0.3048)
			(stroke
				(width 0.1)
				(type default)
			)
			(layer "F.Fab")
		)
		(fp_line
			(start 0.67945 0.3048)
			(end 0.120396 0.3048)
			(stroke
				(width 0.1)
				(type default)
			)
			(layer "F.Fab")
		)
		(pad "1" smd circle
			(at -0.40005 0)
			(size 0 0)
			(layers "F.Cu" "F.Mask" "F.Paste")
			(net "GND")
		)
		(pad "2" smd circle
			(at 0.40005 0)
			(size 0 0)
			(layers "F.Cu" "F.Mask" "F.Paste")
			(net "PVCCINFAON_CPU1_VREF")
		)
	)
)
